(kicad_pcb
	(version 20260206)
	(generator "pcbnew")
	(generator_version "10.0")
	(general
		(thickness 1.6)
		(legacy_teardrops no)
	)
	(paper "A4")
	(title_block
		(title "Bryce Canyon_SCC_16316-1_OCP.brd")
		(comment 1 "Bryce Canyon / footprints 1080-1087 of 1561")
	)
	(layers
		(0 "F.Cu" signal "TOP")
		(4 "In1.Cu" signal "L2GND")
		(6 "In2.Cu" signal "L3")
		(8 "In3.Cu" signal "L4VCC")
		(10 "In4.Cu" signal "L5VCC")
		(12 "In5.Cu" signal "L6")
		(14 "In6.Cu" signal "L7GND")
		(2 "B.Cu" signal "BOTTOM")
		(9 "F.Adhes" user "F.Adhesive")
		(11 "B.Adhes" user "B.Adhesive")
		(13 "F.Paste" user "Package Geometry/Pastemask Top")
		(15 "B.Paste" user "Package Geometry/Pastemask Bottom")
		(5 "F.SilkS" user "Ref Des/Silkscreen Top")
		(7 "B.SilkS" user "Ref Des/Silkscreen Bottom")
		(1 "F.Mask" user "Board Geometry/Soldermask Top")
		(3 "B.Mask" user "Board Geometry/Soldermask Bottom")
		(17 "Dwgs.User" user "User.Drawings")
		(19 "Cmts.User" user "User.Comments")
		(21 "Eco1.User" user "User.Eco1")
		(23 "Eco2.User" user "User.Eco2")
		(25 "Edge.Cuts" user "Board Geometry/Outline")
		(27 "Margin" user)
		(31 "F.CrtYd" user "Package Geometry/Place Bound Top")
		(29 "B.CrtYd" user "Package Geometry/Place Bound Bottom")
		(35 "F.Fab" user "Ref Des/Assembly Top")
		(33 "B.Fab" user "Ref Des/Assembly Bottom")
	)
	(footprint ""
		(layer "B.Cu")
		(at 110.278418 -69.431662 -90)
		(property "Reference" "C190"
			(at 0 0 90)
			(layer "B.SilkS")
			(hide yes)
			(effects
				(font
					(size 1.27 1.27)
				)
				(justify mirror)
			)
		)
		(property "Value" "SC1KP25V1KX-GP"
			(at 2.8321 -1.7399 270)
			(unlocked yes)
			(layer "B.Fab")
			(hide yes)
			(effects
				(font
					(size 1.016 1.016)
					(thickness 0.1524)
				)
				(justify mirror)
			)
		)
		(property "Device Type" "C0201H13"
			(at 2.8321 -3.2639 270)
			(unlocked yes)
			(layer "B.Fab")
			(hide yes)
			(effects
				(font
					(size 1.016 1.016)
					(thickness 0.1524)
				)
				(justify mirror)
			)
		)
		(duplicate_pad_numbers_are_jumpers no)
		(fp_rect
			(start 0.2794 0.6477)
			(end -0.2794 -0.6477)
			(stroke
				(width 0)
				(type default)
			)
			(fill no)
			(layer "B.CrtYd")
		)
		(fp_rect
			(start 0.2794 0.6477)
			(end -0.2794 -0.6477)
			(stroke
				(width 0)
				(type default)
			)
			(fill no)
			(layer "B.Fab")
		)
		(pad "1" smd custom
			(at 0 -0.2794 90)
			(size 0.0762 0.0762)
			(layers "B.Cu" "B.Mask" "B.Paste")
			(net "P0V9")
			(options
				(clearance outline)
				(anchor circle)
			)
			(primitives
				(gr_poly
					(pts
						(arc
							(start 0.1524 0.127)
							(mid 0.137521 0.162921)
							(end 0.1016 0.1778)
						)
						(arc
							(start -0.1016 0.1778)
							(mid -0.137521 0.162921)
							(end -0.1524 0.127)
						)
						(arc
							(start -0.1524 -0.127)
							(mid -0.137521 -0.162921)
							(end -0.1016 -0.1778)
						)
						(arc
							(start 0.1016 -0.1778)
							(mid 0.137521 -0.162921)
							(end 0.1524 -0.127)
						)
					)
					(width 0)
					(fill yes)
				)
			)
		)
		(pad "2" smd custom
			(at 0 0.2794 90)
			(size 0.0762 0.0762)
			(layers "B.Cu" "B.Mask" "B.Paste")
			(net "GND")
			(options
				(clearance outline)
				(anchor circle)
			)
			(primitives
				(gr_poly
					(pts
						(arc
							(start 0.1524 0.127)
							(mid 0.137521 0.162921)
							(end 0.1016 0.1778)
						)
						(arc
							(start -0.1016 0.1778)
							(mid -0.137521 0.162921)
							(end -0.1524 0.127)
						)
						(arc
							(start -0.1524 -0.127)
							(mid -0.137521 -0.162921)
							(end -0.1016 -0.1778)
						)
						(arc
							(start 0.1016 -0.1778)
							(mid 0.137521 -0.162921)
							(end 0.1524 -0.127)
						)
					)
					(width 0)
					(fill yes)
				)
			)
		)
	)
	(footprint ""
		(layer "B.Cu")
		(at 89.462356 -78.171548)
		(property "Reference" "L5"
			(at 0 0 0)
			(layer "B.SilkS")
			(hide yes)
			(effects
				(font
					(size 1.27 1.27)
				)
				(justify mirror)
			)
		)
		(property "Value" "MPZ2012S601AT-GP"
			(at 0 -4.2418 0)
			(unlocked yes)
			(layer "B.Fab")
			(hide yes)
			(effects
				(font
					(size 1.016 1.016)
					(thickness 0.1524)
				)
				(justify mirror)
			)
		)
		(property "Device Type" "L805H42"
			(at 0 -5.7912 0)
			(unlocked yes)
			(layer "B.Fab")
			(hide yes)
			(effects
				(font
					(size 1.016 1.016)
					(thickness 0.1524)
				)
				(justify mirror)
			)
		)
		(duplicate_pad_numbers_are_jumpers no)
		(fp_line
			(start -0.889 -1.7018)
			(end -0.889 1.7018)
			(stroke
				(width 0.1524)
				(type default)
			)
			(layer "B.SilkS")
		)
		(fp_line
			(start -0.889 1.7018)
			(end 0.889 1.7018)
			(stroke
				(width 0.1524)
				(type default)
			)
			(layer "B.SilkS")
		)
		(fp_line
			(start 0.889 -1.7018)
			(end -0.889 -1.7018)
			(stroke
				(width 0.1524)
				(type default)
			)
			(layer "B.SilkS")
		)
		(fp_line
			(start 0.889 1.7018)
			(end 0.889 -1.7018)
			(stroke
				(width 0.1524)
				(type default)
			)
			(layer "B.SilkS")
		)
		(fp_rect
			(start 0.9652 1.778)
			(end -0.9652 -1.778)
			(stroke
				(width 0)
				(type default)
			)
			(fill no)
			(layer "B.CrtYd")
		)
		(fp_rect
			(start 0.9652 1.778)
			(end -0.9652 -1.778)
			(stroke
				(width 0)
				(type default)
			)
			(fill no)
			(layer "B.Fab")
		)
		(pad "1" smd rect
			(at 0 -0.9652 180)
			(size 1.397 1.143)
			(layers "B.Cu" "B.Mask" "B.Paste")
			(net "SYSPLL_VDDA09")
		)
		(pad "2" smd rect
			(at 0 0.9652 180)
			(size 1.397 1.143)
			(layers "B.Cu" "B.Mask" "B.Paste")
			(net "P0V9")
		)
	)
	(footprint ""
		(layer "B.Cu")
		(at 181.229 -34.7853)
		(property "Reference" "R251"
			(at 0 0 0)
			(layer "B.SilkS")
			(hide yes)
			(effects
				(font
					(size 1.27 1.27)
				)
				(justify mirror)
			)
		)
		(property "Value" "10KR2F-2-GP"
			(at -0.064008 -3.993896 0)
			(unlocked yes)
			(layer "B.Fab")
			(hide yes)
			(effects
				(font
					(size 1.016 1.016)
					(thickness 0.1524)
				)
				(justify mirror)
			)
		)
		(property "Device Type" "R402H16"
			(at -0.064008 -5.517896 0)
			(unlocked yes)
			(layer "B.Fab")
			(hide yes)
			(effects
				(font
					(size 1.016 1.016)
					(thickness 0.1524)
				)
				(justify mirror)
			)
		)
		(duplicate_pad_numbers_are_jumpers no)
		(fp_line
			(start -0.508 -0.9398)
			(end 0.508 -0.9398)
			(stroke
				(width 0.1524)
				(type default)
			)
			(layer "B.SilkS")
		)
		(fp_line
			(start 0.508 -0.9398)
			(end 0.508 0.9398)
			(stroke
				(width 0.1524)
				(type default)
			)
			(layer "B.SilkS")
		)
		(fp_rect
			(start 0.508 0.9398)
			(end -0.508 -0.9398)
			(stroke
				(width 0)
				(type default)
			)
			(fill no)
			(layer "B.CrtYd")
		)
		(fp_rect
			(start 0.508 0.9398)
			(end -0.508 -0.9398)
			(stroke
				(width 0)
				(type default)
			)
			(fill no)
			(layer "B.Fab")
		)
		(pad "1" smd custom
			(at 0 -0.4445 180)
			(size 0.1397 0.1397)
			(layers "B.Cu" "B.Mask" "B.Paste")
			(net "P1V8_C")
			(options
				(clearance outline)
				(anchor circle)
			)
			(primitives
				(gr_poly
					(pts
						(arc
							(start -0.1778 0.2794)
							(mid -0.249642 0.249642)
							(end -0.2794 0.1778)
						)
						(arc
							(start -0.2794 -0.1778)
							(mid -0.249642 -0.249642)
							(end -0.1778 -0.2794)
						)
						(arc
							(start 0.1778 -0.2794)
							(mid 0.249642 -0.249642)
							(end 0.2794 -0.1778)
						)
						(arc
							(start 0.2794 0.1778)
							(mid 0.249642 0.249642)
							(end 0.1778 0.2794)
						)
					)
					(width 0)
					(fill yes)
				)
			)
		)
		(pad "2" smd custom
			(at 0 0.4445 180)
			(size 0.1397 0.1397)
			(layers "B.Cu" "B.Mask" "B.Paste")
			(net "SYS_DBMODE0")
			(options
				(clearance outline)
				(anchor circle)
			)
			(primitives
				(gr_poly
					(pts
						(arc
							(start -0.1778 0.2794)
							(mid -0.249642 0.249642)
							(end -0.2794 0.1778)
						)
						(arc
							(start -0.2794 -0.1778)
							(mid -0.249642 -0.249642)
							(end -0.1778 -0.2794)
						)
						(arc
							(start 0.1778 -0.2794)
							(mid 0.249642 -0.249642)
							(end 0.2794 -0.1778)
						)
						(arc
							(start 0.2794 0.1778)
							(mid 0.249642 0.249642)
							(end 0.1778 0.2794)
						)
					)
					(width 0)
					(fill yes)
				)
			)
		)
	)
	(footprint ""
		(layer "B.Cu")
		(at 183.668416 -89.671652 90)
		(property "Reference" "C628"
			(at 0 0 90)
			(layer "B.SilkS")
			(hide yes)
			(effects
				(font
					(size 1.27 1.27)
				)
				(justify mirror)
			)
		)
		(property "Value" "SC10U6D3V5KX-4GP"
			(at 0.0762 -6.1214 90)
			(unlocked yes)
			(layer "B.Fab")
			(hide yes)
			(effects
				(font
					(size 1.016 1.016)
					(thickness 0.1524)
				)
				(justify mirror)
			)
		)
		(property "Device Type" "C805H58"
			(at 0.0762 -8.1534 90)
			(unlocked yes)
			(layer "B.Fab")
			(hide yes)
			(effects
				(font
					(size 1.016 1.016)
					(thickness 0.1524)
				)
				(justify mirror)
			)
		)
		(duplicate_pad_numbers_are_jumpers no)
		(fp_line
			(start -0.635 0)
			(end 0.635 0)
			(stroke
				(width 0.508)
				(type default)
			)
			(layer "B.SilkS")
		)
		(fp_rect
			(start 0.9652 1.778)
			(end -0.9652 -1.778)
			(stroke
				(width 0)
				(type default)
			)
			(fill no)
			(layer "B.CrtYd")
		)
		(fp_poly
			(pts
				(xy 0.9652 -1.778) (xy -0.9652 -1.778) (xy -0.9652 1.778) (xy 0.9652 1.778)
			)
			(stroke
				(width 0)
				(type default)
			)
			(fill no)
			(layer "B.Fab")
		)
		(pad "1" smd rect
			(at 0 -0.9652 270)
			(size 1.397 1.143)
			(layers "B.Cu" "B.Mask" "B.Paste")
			(net "P0V975")
		)
		(pad "2" smd rect
			(at 0 0.9652 270)
			(size 1.397 1.143)
			(layers "B.Cu" "B.Mask" "B.Paste")
			(net "GND")
		)
	)
	(footprint ""
		(layer "B.Cu")
		(at 177.811176 -40.269922 90)
		(property "Reference" "C435"
			(at 0 0 90)
			(layer "B.SilkS")
			(hide yes)
			(effects
				(font
					(size 1.27 1.27)
				)
				(justify mirror)
			)
		)
		(property "Value" "SCD1U6D3V1KX-GP"
			(at 2.8321 -1.7399 90)
			(unlocked yes)
			(layer "B.Fab")
			(hide yes)
			(effects
				(font
					(size 1.016 1.016)
					(thickness 0.1524)
				)
				(justify mirror)
			)
		)
		(property "Device Type" "C0201H13"
			(at 2.8321 -3.2639 90)
			(unlocked yes)
			(layer "B.Fab")
			(hide yes)
			(effects
				(font
					(size 1.016 1.016)
					(thickness 0.1524)
				)
				(justify mirror)
			)
		)
		(duplicate_pad_numbers_are_jumpers no)
		(fp_rect
			(start 0.2794 0.6477)
			(end -0.2794 -0.6477)
			(stroke
				(width 0)
				(type default)
			)
			(fill no)
			(layer "B.CrtYd")
		)
		(fp_rect
			(start 0.2794 0.6477)
			(end -0.2794 -0.6477)
			(stroke
				(width 0)
				(type default)
			)
			(fill no)
			(layer "B.Fab")
		)
		(pad "1" smd custom
			(at 0 -0.2794 270)
			(size 0.0762 0.0762)
			(layers "B.Cu" "B.Mask" "B.Paste")
			(net "P0V975")
			(options
				(clearance outline)
				(anchor circle)
			)
			(primitives
				(gr_poly
					(pts
						(arc
							(start 0.1524 0.127)
							(mid 0.137521 0.162921)
							(end 0.1016 0.1778)
						)
						(arc
							(start -0.1016 0.1778)
							(mid -0.137521 0.162921)
							(end -0.1524 0.127)
						)
						(arc
							(start -0.1524 -0.127)
							(mid -0.137521 -0.162921)
							(end -0.1016 -0.1778)
						)
						(arc
							(start 0.1016 -0.1778)
							(mid 0.137521 -0.162921)
							(end 0.1524 -0.127)
						)
					)
					(width 0)
					(fill yes)
				)
			)
		)
		(pad "2" smd custom
			(at 0 0.2794 270)
			(size 0.0762 0.0762)
			(layers "B.Cu" "B.Mask" "B.Paste")
			(net "GND")
			(options
				(clearance outline)
				(anchor circle)
			)
			(primitives
				(gr_poly
					(pts
						(arc
							(start 0.1524 0.127)
							(mid 0.137521 0.162921)
							(end 0.1016 0.1778)
						)
						(arc
							(start -0.1016 0.1778)
							(mid -0.137521 0.162921)
							(end -0.1524 0.127)
						)
						(arc
							(start -0.1524 -0.127)
							(mid -0.137521 -0.162921)
							(end -0.1016 -0.1778)
						)
						(arc
							(start 0.1016 -0.1778)
							(mid 0.137521 -0.162921)
							(end 0.1524 -0.127)
						)
					)
					(width 0)
					(fill yes)
				)
			)
		)
	)
	(footprint ""
		(layer "B.Cu")
		(at 117.2591 -57.4802)
		(property "Reference" "C585"
			(at 0 0 0)
			(layer "B.SilkS")
			(hide yes)
			(effects
				(font
					(size 1.27 1.27)
				)
				(justify mirror)
			)
		)
		(property "Value" "SCD1U6D3V1KX-GP"
			(at 2.8321 -1.7399 0)
			(unlocked yes)
			(layer "B.Fab")
			(hide yes)
			(effects
				(font
					(size 1.016 1.016)
					(thickness 0.1524)
				)
				(justify mirror)
			)
		)
		(property "Device Type" "C0201H13"
			(at 2.8321 -3.2639 0)
			(unlocked yes)
			(layer "B.Fab")
			(hide yes)
			(effects
				(font
					(size 1.016 1.016)
					(thickness 0.1524)
				)
				(justify mirror)
			)
		)
		(duplicate_pad_numbers_are_jumpers no)
		(fp_rect
			(start 0.2794 0.6477)
			(end -0.2794 -0.6477)
			(stroke
				(width 0)
				(type default)
			)
			(fill no)
			(layer "B.CrtYd")
		)
		(fp_rect
			(start 0.2794 0.6477)
			(end -0.2794 -0.6477)
			(stroke
				(width 0)
				(type default)
			)
			(fill no)
			(layer "B.Fab")
		)
		(pad "1" smd custom
			(at 0 -0.2794 180)
			(size 0.0762 0.0762)
			(layers "B.Cu" "B.Mask" "B.Paste")
			(net "GB_VDDA")
			(options
				(clearance outline)
				(anchor circle)
			)
			(primitives
				(gr_poly
					(pts
						(arc
							(start 0.1524 0.127)
							(mid 0.137521 0.162921)
							(end 0.1016 0.1778)
						)
						(arc
							(start -0.1016 0.1778)
							(mid -0.137521 0.162921)
							(end -0.1524 0.127)
						)
						(arc
							(start -0.1524 -0.127)
							(mid -0.137521 -0.162921)
							(end -0.1016 -0.1778)
						)
						(arc
							(start 0.1016 -0.1778)
							(mid 0.137521 -0.162921)
							(end 0.1524 -0.127)
						)
					)
					(width 0)
					(fill yes)
				)
			)
		)
		(pad "2" smd custom
			(at 0 0.2794 180)
			(size 0.0762 0.0762)
			(layers "B.Cu" "B.Mask" "B.Paste")
			(net "GND")
			(options
				(clearance outline)
				(anchor circle)
			)
			(primitives
				(gr_poly
					(pts
						(arc
							(start 0.1524 0.127)
							(mid 0.137521 0.162921)
							(end 0.1016 0.1778)
						)
						(arc
							(start -0.1016 0.1778)
							(mid -0.137521 0.162921)
							(end -0.1524 0.127)
						)
						(arc
							(start -0.1524 -0.127)
							(mid -0.137521 -0.162921)
							(end -0.1016 -0.1778)
						)
						(arc
							(start 0.1016 -0.1778)
							(mid 0.137521 -0.162921)
							(end 0.1524 -0.127)
						)
					)
					(width 0)
					(fill yes)
				)
			)
		)
	)
	(footprint ""
		(layer "B.Cu")
		(at 114.7191 -57.4802)
		(property "Reference" "C254"
			(at 0 0 0)
			(layer "B.SilkS")
			(hide yes)
			(effects
				(font
					(size 1.27 1.27)
				)
				(justify mirror)
			)
		)
		(property "Value" "SCD1U6D3V1KX-GP"
			(at 2.8321 -1.7399 0)
			(unlocked yes)
			(layer "B.Fab")
			(hide yes)
			(effects
				(font
					(size 1.016 1.016)
					(thickness 0.1524)
				)
				(justify mirror)
			)
		)
		(property "Device Type" "C0201H13"
			(at 2.8321 -3.2639 0)
			(unlocked yes)
			(layer "B.Fab")
			(hide yes)
			(effects
				(font
					(size 1.016 1.016)
					(thickness 0.1524)
				)
				(justify mirror)
			)
		)
		(duplicate_pad_numbers_are_jumpers no)
		(fp_rect
			(start 0.2794 0.6477)
			(end -0.2794 -0.6477)
			(stroke
				(width 0)
				(type default)
			)
			(fill no)
			(layer "B.CrtYd")
		)
		(fp_rect
			(start 0.2794 0.6477)
			(end -0.2794 -0.6477)
			(stroke
				(width 0)
				(type default)
			)
			(fill no)
			(layer "B.Fab")
		)
		(pad "1" smd custom
			(at 0 -0.2794 180)
			(size 0.0762 0.0762)
			(layers "B.Cu" "B.Mask" "B.Paste")
			(net "GB_VDDA")
			(options
				(clearance outline)
				(anchor circle)
			)
			(primitives
				(gr_poly
					(pts
						(arc
							(start 0.1524 0.127)
							(mid 0.137521 0.162921)
							(end 0.1016 0.1778)
						)
						(arc
							(start -0.1016 0.1778)
							(mid -0.137521 0.162921)
							(end -0.1524 0.127)
						)
						(arc
							(start -0.1524 -0.127)
							(mid -0.137521 -0.162921)
							(end -0.1016 -0.1778)
						)
						(arc
							(start 0.1016 -0.1778)
							(mid 0.137521 -0.162921)
							(end 0.1524 -0.127)
						)
					)
					(width 0)
					(fill yes)
				)
			)
		)
		(pad "2" smd custom
			(at 0 0.2794 180)
			(size 0.0762 0.0762)
			(layers "B.Cu" "B.Mask" "B.Paste")
			(net "GND")
			(options
				(clearance outline)
				(anchor circle)
			)
			(primitives
				(gr_poly
					(pts
						(arc
							(start 0.1524 0.127)
							(mid 0.137521 0.162921)
							(end 0.1016 0.1778)
						)
						(arc
							(start -0.1016 0.1778)
							(mid -0.137521 0.162921)
							(end -0.1524 0.127)
						)
						(arc
							(start -0.1524 -0.127)
							(mid -0.137521 -0.162921)
							(end -0.1016 -0.1778)
						)
						(arc
							(start 0.1016 -0.1778)
							(mid 0.137521 -0.162921)
							(end 0.1524 -0.127)
						)
					)
					(width 0)
					(fill yes)
				)
			)
		)
	)
	(footprint ""
		(layer "B.Cu")
		(at 184.465468 -43.19651 90)
		(property "Reference" "C458"
			(at 0 0 90)
			(layer "B.SilkS")
			(hide yes)
			(effects
				(font
					(size 1.27 1.27)
				)
				(justify mirror)
			)
		)
		(property "Value" "SCD1U6D3V1KX-GP"
			(at 2.8321 -1.7399 90)
			(unlocked yes)
			(layer "B.Fab")
			(hide yes)
			(effects
				(font
					(size 1.016 1.016)
					(thickness 0.1524)
				)
				(justify mirror)
			)
		)
		(property "Device Type" "C0201H13"
			(at 2.8321 -3.2639 90)
			(unlocked yes)
			(layer "B.Fab")
			(hide yes)
			(effects
				(font
					(size 1.016 1.016)
					(thickness 0.1524)
				)
				(justify mirror)
			)
		)
		(duplicate_pad_numbers_are_jumpers no)
		(fp_rect
			(start 0.2794 0.6477)
			(end -0.2794 -0.6477)
			(stroke
				(width 0)
				(type default)
			)
			(fill no)
			(layer "B.CrtYd")
		)
		(fp_rect
			(start 0.2794 0.6477)
			(end -0.2794 -0.6477)
			(stroke
				(width 0)
				(type default)
			)
			(fill no)
			(layer "B.Fab")
		)
		(pad "1" smd custom
			(at 0 -0.2794 270)
			(size 0.0762 0.0762)
			(layers "B.Cu" "B.Mask" "B.Paste")
			(net "P1V8_C")
			(options
				(clearance outline)
				(anchor circle)
			)
			(primitives
				(gr_poly
					(pts
						(arc
							(start 0.1524 0.127)
							(mid 0.137521 0.162921)
							(end 0.1016 0.1778)
						)
						(arc
							(start -0.1016 0.1778)
							(mid -0.137521 0.162921)
							(end -0.1524 0.127)
						)
						(arc
							(start -0.1524 -0.127)
							(mid -0.137521 -0.162921)
							(end -0.1016 -0.1778)
						)
						(arc
							(start 0.1016 -0.1778)
							(mid 0.137521 -0.162921)
							(end 0.1524 -0.127)
						)
					)
					(width 0)
					(fill yes)
				)
			)
		)
		(pad "2" smd custom
			(at 0 0.2794 270)
			(size 0.0762 0.0762)
			(layers "B.Cu" "B.Mask" "B.Paste")
			(net "GND")
			(options
				(clearance outline)
				(anchor circle)
			)
			(primitives
				(gr_poly
					(pts
						(arc
							(start 0.1524 0.127)
							(mid 0.137521 0.162921)
							(end 0.1016 0.1778)
						)
						(arc
							(start -0.1016 0.1778)
							(mid -0.137521 0.162921)
							(end -0.1524 0.127)
						)
						(arc
							(start -0.1524 -0.127)
							(mid -0.137521 -0.162921)
							(end -0.1016 -0.1778)
						)
						(arc
							(start 0.1016 -0.1778)
							(mid 0.137521 -0.162921)
							(end 0.1524 -0.127)
						)
					)
					(width 0)
					(fill yes)
				)
			)
		)
	)
)
